# BASEBOARD_FAB2 (Tioga Pass) — schematic netlist excerpt (pin names and nets, part order shuffled) for the footprints in the layout excerpt that follows; sources: Cadence DE-HDL packaged netlist, KiCad conversion of Wiwynn_Tioga_Pass_MB.brd

CR6W1  DIODE  BAT54WS IC  pkg SMLF  page 247 : C = FM_CPU_CATERR_LVT3_N ; A = FM_CPU_CATERR_MSMI_LVT3_N
C9P26  CAP  10UF 16V 10% X6S  pkg 0805  page 207 : A = VR_FET_SW_P12V_STBY_PVCCIN_CPU1 ; B = GND
C4P9  CAP  47UF 4V 20% X6S  pkg 0805  page 42 : A = PVCCIO_CPU0 ; B = GND

(kicad_pcb
	(version 20260206)
	(generator "pcbnew")
	(generator_version "10.0")
	(general
		(thickness 1.6)
		(legacy_teardrops no)
	)
	(paper "A4")
	(title_block
		(title "Wiwynn_Tioga_Pass_MB.brd")
		(comment 1 "Tioga Pass / footprints 4766-4768 of 4770")
	)
	(layers
		(0 "F.Cu" signal "TOP")
		(4 "In1.Cu" signal "L2GND")
		(6 "In2.Cu" signal "L3")
		(8 "In3.Cu" signal "L4GND")
		(10 "In4.Cu" signal "L5")
		(12 "In5.Cu" signal "L6GND")
		(14 "In6.Cu" signal "L7VCC")
		(16 "In7.Cu" signal "L8VCC")
		(18 "In8.Cu" signal "L9GND")
		(20 "In9.Cu" signal "L10")
		(22 "In10.Cu" signal "L11GND")
		(24 "In11.Cu" signal "L12")
		(26 "In12.Cu" signal "L13GND")
		(2 "B.Cu" signal "BOTTOM")
		(9 "F.Adhes" user "F.Adhesive")
		(11 "B.Adhes" user "B.Adhesive")
		(13 "F.Paste" user "Package Geometry/Pastemask Top")
		(15 "B.Paste" user "Package Geometry/Pastemask Bottom")
		(5 "F.SilkS" user "Ref Des/Silkscreen Top")
		(7 "B.SilkS" user "Ref Des/Silkscreen Bottom")
		(1 "F.Mask" user "Board Geometry/Soldermask Top")
		(3 "B.Mask" user "Board Geometry/Soldermask Bottom")
		(17 "Dwgs.User" user "User.Drawings")
		(19 "Cmts.User" user "User.Comments")
		(21 "Eco1.User" user "User.Eco1")
		(23 "Eco2.User" user "User.Eco2")
		(25 "Edge.Cuts" user "Board Geometry/Outline")
		(27 "Margin" user)
		(31 "F.CrtYd" user "Package Geometry/Place Bound Top")
		(29 "B.CrtYd" user "Package Geometry/Place Bound Bottom")
		(35 "F.Fab" user "Ref Des/Assembly Top")
		(33 "B.Fab" user "Ref Des/Assembly Bottom")
	)
	(footprint ""
		(layer "B.Cu")
		(at 470.8906 -131.2164 180)
		(property "Reference" "CR6W1"
			(at -1.06934 -0.39116 270)
			(unlocked yes)
			(layer "B.SilkS")
			(effects
				(font
					(size 0.4064 0.254)
					(thickness 0.1524)
				)
				(justify left mirror)
			)
		)
		(property "Value" ""
			(at 0 0 0)
			(layer "B.Fab")
			(effects
				(font
					(size 1.27 1.27)
				)
				(justify mirror)
			)
		)
		(duplicate_pad_numbers_are_jumpers no)
		(fp_line
			(start 1.18237 1.568958)
			(end 0.701548 0.736092)
			(stroke
				(width 0.1524)
				(type default)
			)
			(layer "B.SilkS")
		)
		(fp_line
			(start 0.701548 2.480564)
			(end 0.701548 1.568958)
			(stroke
				(width 0.1524)
				(type default)
			)
			(layer "B.SilkS")
		)
		(fp_line
			(start 0.701548 1.568958)
			(end 1.18237 1.568958)
			(stroke
				(width 0.1524)
				(type default)
			)
			(layer "B.SilkS")
		)
		(fp_line
			(start 0.701548 0.736092)
			(end 0.220726 1.568958)
			(stroke
				(width 0.1524)
				(type default)
			)
			(layer "B.SilkS")
		)
		(fp_line
			(start 0.701548 -0.38735)
			(end 0.701548 0.736092)
			(stroke
				(width 0.1524)
				(type default)
			)
			(layer "B.SilkS")
		)
		(fp_line
			(start 0.220726 1.568958)
			(end 0.701548 1.568958)
			(stroke
				(width 0.1524)
				(type default)
			)
			(layer "B.SilkS")
		)
		(fp_line
			(start 0.220726 0.736092)
			(end 1.18237 0.736092)
			(stroke
				(width 0.1524)
				(type default)
			)
			(layer "B.SilkS")
		)
		(fp_poly
			(pts
				(xy 0.67437 0.24384) (xy 0.67437 2.04216) (xy -0.67437 2.04216) (xy -0.67437 0.24384)
			)
			(stroke
				(width 0)
				(type default)
			)
			(fill no)
			(layer "B.CrtYd")
		)
		(fp_line
			(start 1.17602 1.554734)
			(end 0.695198 0.721868)
			(stroke
				(width 0.1)
				(type default)
			)
			(layer "B.Fab")
		)
		(fp_line
			(start 0.695198 1.554734)
			(end 0.695198 2.46634)
			(stroke
				(width 0.1)
				(type default)
			)
			(layer "B.Fab")
		)
		(fp_line
			(start 0.695198 0.721868)
			(end 0.695198 -0.401574)
			(stroke
				(width 0.1)
				(type default)
			)
			(layer "B.Fab")
		)
		(fp_line
			(start 0.695198 0.721868)
			(end 0.214376 1.554734)
			(stroke
				(width 0.1)
				(type default)
			)
			(layer "B.Fab")
		)
		(fp_line
			(start 0.67437 2.04216)
			(end -0.67437 2.04216)
			(stroke
				(width 0.1)
				(type default)
			)
			(layer "B.Fab")
		)
		(fp_line
			(start 0.67437 0.24384)
			(end 0.67437 2.04216)
			(stroke
				(width 0.1)
				(type default)
			)
			(layer "B.Fab")
		)
		(fp_line
			(start 0.214376 1.554734)
			(end 1.17602 1.554734)
			(stroke
				(width 0.1)
				(type default)
			)
			(layer "B.Fab")
		)
		(fp_line
			(start 0.214376 0.721868)
			(end 1.17602 0.721868)
			(stroke
				(width 0.1)
				(type default)
			)
			(layer "B.Fab")
		)
		(fp_line
			(start -0.67437 2.04216)
			(end -0.67437 0.24384)
			(stroke
				(width 0.1)
				(type default)
			)
			(layer "B.Fab")
		)
		(fp_line
			(start -0.67437 0.24384)
			(end 0.67437 0.24384)
			(stroke
				(width 0.1)
				(type default)
			)
			(layer "B.Fab")
		)
		(pad "1" smd rect
			(at 0 0)
			(size 0.4064 1.016)
			(layers "B.Cu" "B.Mask" "B.Paste")
			(net "FM_CPU_CATERR_LVT3_N")
		)
		(pad "2" smd rect
			(at 0 2.286)
			(size 0.4064 1.016)
			(layers "B.Cu" "B.Mask" "B.Paste")
			(net "FM_CPU_CATERR_MSMI_LVT3_N")
		)
	)
	(footprint ""
		(layer "B.Cu")
		(at 278.703024 -71.714614 180)
		(property "Reference" "C4P9"
			(at 0 0 0)
			(layer "B.SilkS")
			(hide yes)
			(effects
				(font
					(size 1.27 1.27)
				)
				(justify mirror)
			)
		)
		(property "Value" ""
			(at 0 0 0)
			(layer "B.Fab")
			(effects
				(font
					(size 1.27 1.27)
				)
				(justify mirror)
			)
		)
		(duplicate_pad_numbers_are_jumpers no)
		(fp_poly
			(pts
				(xy 0.7239 -0.2159) (xy -0.7239 -0.2159) (xy -0.7239 1.9939) (xy 0.7239 1.9939)
			)
			(stroke
				(width 0)
				(type default)
			)
			(fill no)
			(layer "B.CrtYd")
		)
		(fp_line
			(start 0.7239 1.9939)
			(end -0.7239 1.9939)
			(stroke
				(width 0.1)
				(type default)
			)
			(layer "B.Fab")
		)
		(fp_line
			(start 0.7239 -0.2159)
			(end 0.7239 1.9939)
			(stroke
				(width 0.1)
				(type default)
			)
			(layer "B.Fab")
		)
		(fp_line
			(start -0.7239 1.9939)
			(end -0.7239 -0.2159)
			(stroke
				(width 0.1)
				(type default)
			)
			(layer "B.Fab")
		)
		(fp_line
			(start -0.7239 -0.2159)
			(end 0.7239 -0.2159)
			(stroke
				(width 0.1)
				(type default)
			)
			(layer "B.Fab")
		)
		(pad "1" smd rect
			(at 0 0)
			(size 1.27 1.016)
			(layers "B.Cu" "B.Mask" "B.Paste")
			(net "PVCCIO_CPU0")
		)
		(pad "2" smd rect
			(at 0 1.778)
			(size 1.27 1.016)
			(layers "B.Cu" "B.Mask" "B.Paste")
			(net "GND")
		)
		(zone
			(layer "B.Cu")
			(hatch none 0.5)
			(connect_pads
				(clearance 0)
			)
			(min_thickness 0.25)
			(keepout
				(tracks not_allowed)
				(vias allowed)
				(pads allowed)
				(copperpour not_allowed)
				(footprints allowed)
			)
			(placement
				(enabled no)
				(sheetname "")
			)
			(fill
				(thermal_gap 0.5)
				(thermal_bridge_width 0.5)
				(island_removal_mode 0)
			)
			(polygon
				(pts
					(xy 278.068024 -72.222614) (xy 279.338024 -72.222614) (xy 279.338024 -72.984614) (xy 278.068024 -72.984614)
				)
			)
		)
	)
	(footprint ""
		(layer "B.Cu")
		(at 32.832802 -64.774064 90)
		(property "Reference" "C9P26"
			(at 0 0 90)
			(layer "B.SilkS")
			(hide yes)
			(effects
				(font
					(size 1.27 1.27)
				)
				(justify mirror)
			)
		)
		(property "Value" ""
			(at 0 0 90)
			(layer "B.Fab")
			(effects
				(font
					(size 1.27 1.27)
				)
				(justify mirror)
			)
		)
		(duplicate_pad_numbers_are_jumpers no)
		(fp_poly
			(pts
				(xy 0.7239 -0.2159) (xy -0.7239 -0.2159) (xy -0.7239 1.9939) (xy 0.7239 1.9939)
			)
			(stroke
				(width 0)
				(type default)
			)
			(fill no)
			(layer "B.CrtYd")
		)
		(fp_line
			(start 0.7239 -0.2159)
			(end 0.7239 1.9939)
			(stroke
				(width 0.1)
				(type default)
			)
			(layer "B.Fab")
		)
		(fp_line
			(start -0.7239 -0.2159)
			(end 0.7239 -0.2159)
			(stroke
				(width 0.1)
				(type default)
			)
			(layer "B.Fab")
		)
		(fp_line
			(start 0.7239 1.9939)
			(end -0.7239 1.9939)
			(stroke
				(width 0.1)
				(type default)
			)
			(layer "B.Fab")
		)
		(fp_line
			(start -0.7239 1.9939)
			(end -0.7239 -0.2159)
			(stroke
				(width 0.1)
				(type default)
			)
			(layer "B.Fab")
		)
		(pad "1" smd rect
			(at 0 0 270)
			(size 1.27 1.016)
			(layers "B.Cu" "B.Mask" "B.Paste")
			(net "VR_FET_SW_P12V_STBY_PVCCIN_CPU1")
		)
		(pad "2" smd rect
			(at 0 1.778 270)
			(size 1.27 1.016)
			(layers "B.Cu" "B.Mask" "B.Paste")
			(net "GND")
		)
		(zone
			(layer "B.Cu")
			(hatch none 0.5)
			(connect_pads
				(clearance 0)
			)
			(min_thickness 0.25)
			(keepout
				(tracks not_allowed)
				(vias allowed)
				(pads allowed)
				(copperpour not_allowed)
				(footprints allowed)
			)
			(placement
				(enabled no)
				(sheetname "")
			)
			(fill
				(thermal_gap 0.5)
				(thermal_bridge_width 0.5)
				(island_removal_mode 0)
			)
			(polygon
				(pts
					(xy 33.340802 -65.409064) (xy 33.340802 -64.139064) (xy 34.102802 -64.139064) (xy 34.102802 -65.409064)
				)
			)
		)
	)
)
